G04 ================== begin FILE IDENTIFICATION RECORD ==================*
G04 Layout Name:  15669-1.brd*
G04 Film Name:    BSILK*
G04 File Format:  Gerber RS274X*
G04 File Origin:  Cadence Allegro 16.5-S056*
G04 Origin Date:  Wed Nov 16 04:07:58 2016*
G04 *
G04 Layer:  VIA CLASS/FILMMASKBOTTOM*
G04 Layer:  REF DES/ASSEMBLY_BOTTOM*
G04 Layer:  PACKAGE GEOMETRY/SILKSCREEN_BOTTOM*
G04 Layer:  DRAWING FORMAT/LAYER_PCB_STORY*
G04 Layer:  DRAWING FORMAT/LAYER_SILK_B*
G04 Layer:  BOARD GEOMETRY/SILKSCREEN_BOTTOM*
G04 *
G04 Offset:    (0.00 0.00)*
G04 Mirror:    No*
G04 Mode:      Positive*
G04 Rotation:  0*
G04 FullContactRelief:  No*
G04 UndefLineWidth:     6.00*
G04 ================== end FILE IDENTIFICATION RECORD ====================*
%FSLAX35Y35*MOIN*%
%IR0*IPPOS*OFA0.00000B0.00000*MIA0B0*SFA1.00000B1.00000*%
%ADD10C,.024*%
%ADD11C,.01*%
%ADD12C,.02*%
%ADD13C,.006*%
G75*
%LPD*%
G75*
G54D10*
X302500Y583000D03*
X297500D03*
Y588000D03*
X302500D03*
X300000Y585500D03*
Y1421500D03*
X302500Y1424000D03*
X297500D03*
Y1419000D03*
X302500D03*
X370000Y411000D03*
Y405500D03*
X375500D03*
X381000D03*
X375500Y411000D03*
X381000D03*
X359000D03*
X364500D03*
Y405500D03*
X359000D03*
X370000Y400000D03*
X381000D03*
X375500D03*
X370000Y389000D03*
Y394500D03*
X375500D03*
Y389000D03*
X381000D03*
Y394500D03*
X364500Y400000D03*
X365000Y394500D03*
Y389000D03*
X359000D03*
Y394500D03*
Y400000D03*
X370000Y841000D03*
Y835500D03*
X375500D03*
X381000D03*
X375500Y841000D03*
X381000D03*
X359000D03*
X364500D03*
Y835500D03*
X359000D03*
X370000Y830000D03*
X381000D03*
X375500D03*
X370000Y819000D03*
Y824500D03*
X375500D03*
Y819000D03*
X381000D03*
Y824500D03*
X364500Y830000D03*
X365000Y824500D03*
Y819000D03*
X359000D03*
Y824500D03*
Y830000D03*
X370000Y1212500D03*
Y1207000D03*
X375500D03*
X381000D03*
X375500Y1212500D03*
X381000D03*
X359000D03*
X364500D03*
Y1207000D03*
X359000D03*
X370000Y1201500D03*
X381000D03*
X375500D03*
X370000Y1190500D03*
Y1196000D03*
X375500D03*
Y1190500D03*
X381000D03*
Y1196000D03*
X364500Y1201500D03*
X365000Y1196000D03*
Y1190500D03*
X359000D03*
Y1196000D03*
Y1201500D03*
Y1705500D03*
Y1700000D03*
Y1694500D03*
Y1689000D03*
X365000D03*
Y1694500D03*
X364500Y1700000D03*
Y1705500D03*
Y1711000D03*
X359000D03*
X381000D03*
X375500D03*
X381000Y1705500D03*
X375500D03*
X381000Y1694500D03*
Y1689000D03*
X375500D03*
Y1694500D03*
X370000D03*
Y1689000D03*
Y1705500D03*
Y1711000D03*
X381000Y1700000D03*
X375500D03*
X370000D03*
X891500Y1712000D03*
X895500D03*
Y1708000D03*
X891500D03*
G54D11*
G01X0Y39059D02*
Y8350D01*
G01Y282366D02*
Y251657D01*
G01Y525673D02*
Y494965D01*
G01Y1023787D02*
Y993079D01*
G01Y1961500D02*
Y1930791D01*
G01X1037402Y25827D02*
Y56535D01*
G01Y315591D02*
Y284882D01*
G01Y543937D02*
Y574646D01*
G01Y833701D02*
Y802992D01*
G01Y1062047D02*
Y1092756D01*
G01Y1351811D02*
Y1321102D01*
G01Y1767835D02*
Y1737126D01*
G01Y1987598D02*
Y1956890D01*
G54D12*
G01X-106883Y-224955D02*
Y-304955D01*
G01Y-260455D02*
X1019417D01*
G01X-106883Y-304955D02*
X1019417D01*
G01X-110883Y-208955D02*
G02I-12000J0D01*
G01X-116033D02*
G02I-6850J0D01*
G01X-122883Y-224955D02*
Y-192955D01*
G01X-106883Y-208955D02*
X-138883D01*
G01X-106883Y-224955D02*
X1019417D01*
G01X231917D02*
Y-304955D01*
G01X369417Y-224955D02*
Y-304955D01*
G01X484417Y-224955D02*
Y-304955D01*
G01X651917Y-224955D02*
Y-304955D01*
G01X821917Y-224955D02*
Y-304955D01*
G01X1019417Y-224955D02*
Y-304955D01*
G01X1047417Y-208955D02*
G02I-12000J0D01*
G01X1042267D02*
G02I-6850J0D01*
G01X1035417Y-224955D02*
Y-192955D01*
G01X1051417Y-208955D02*
X1019417D01*
G54D13*
G01X-90900Y-277455D02*
Y-294955D01*
X-82166D01*
G01X-69033Y-283289D02*
Y-294955D01*
G01Y-278622D02*
X-69470Y-278330D01*
Y-277747D01*
X-69033Y-277455D01*
X-68596Y-277747D01*
Y-278330D01*
X-69033Y-278622D01*
G01X-54590Y-299330D02*
X-53061Y-300497D01*
X-51315Y-300788D01*
X-49787Y-300497D01*
X-48476Y-299039D01*
X-47603Y-296997D01*
Y-283289D01*
G01Y-285622D02*
X-48476Y-284455D01*
X-49787Y-283580D01*
X-51315Y-283289D01*
X-53061Y-283872D01*
X-54153Y-285038D01*
X-55027Y-287080D01*
X-55463Y-289122D01*
X-55245Y-290872D01*
X-54371Y-292914D01*
X-53061Y-294372D01*
X-51315Y-294955D01*
X-50005Y-294663D01*
X-48476Y-293497D01*
X-47603Y-292331D01*
G01X-37745Y-294955D02*
Y-277455D01*
G01Y-285913D02*
X-36653Y-284455D01*
X-35561Y-283580D01*
X-33815Y-283289D01*
X-32505Y-283580D01*
X-30976Y-284747D01*
X-30321Y-286497D01*
Y-294955D01*
G01X-16533Y-277455D02*
Y-294955D01*
G01X-19590Y-283289D02*
X-13476D01*
G01X-2745Y-294955D02*
Y-283289D01*
G01Y-286205D02*
X-1871Y-284747D01*
X-561Y-283580D01*
X1185Y-283289D01*
X2713Y-283580D01*
X4024Y-284747D01*
X4679Y-286788D01*
Y-294955D01*
G01X18467Y-283289D02*
Y-294955D01*
G01Y-278622D02*
X18030Y-278330D01*
Y-277747D01*
X18467Y-277455D01*
X18904Y-277747D01*
Y-278330D01*
X18467Y-278622D01*
G01X32255Y-294955D02*
Y-283289D01*
G01Y-286205D02*
X33129Y-284747D01*
X34439Y-283580D01*
X36185Y-283289D01*
X37713Y-283580D01*
X39024Y-284747D01*
X39679Y-286788D01*
Y-294955D01*
G01X50410Y-299330D02*
X51939Y-300497D01*
X53685Y-300788D01*
X55213Y-300497D01*
X56524Y-299039D01*
X57397Y-296997D01*
Y-283289D01*
G01Y-285622D02*
X56524Y-284455D01*
X55213Y-283580D01*
X53685Y-283289D01*
X51939Y-283872D01*
X50847Y-285038D01*
X49973Y-287080D01*
X49537Y-289122D01*
X49755Y-290872D01*
X50629Y-292914D01*
X51939Y-294372D01*
X53685Y-294955D01*
X54995Y-294663D01*
X56524Y-293497D01*
X57397Y-292331D01*
G01X84100Y-294955D02*
Y-277455D01*
X89340D01*
X91087Y-278330D01*
X92397Y-280372D01*
X92834Y-282705D01*
X92397Y-285038D01*
X91305Y-286788D01*
X89340Y-287664D01*
X84100D01*
G01X101164Y-294955D02*
Y-277455D01*
X105530D01*
X107277Y-278330D01*
X108587Y-279497D01*
X109679Y-281246D01*
X110552Y-283289D01*
X110770Y-286205D01*
X110552Y-289122D01*
X109679Y-291164D01*
X108587Y-292914D01*
X107277Y-294080D01*
X105530Y-294955D01*
X101164D01*
G01X119100D02*
Y-277455D01*
X124340D01*
X126087Y-278330D01*
X127397Y-280372D01*
X127834Y-282705D01*
X127397Y-285038D01*
X126305Y-286788D01*
X124340Y-287664D01*
X119100D01*
G01X142713Y-285622D02*
X143587Y-284747D01*
X144242Y-283289D01*
X144679Y-281246D01*
X144242Y-279497D01*
X143369Y-278330D01*
X141840Y-277455D01*
X135945D01*
Y-294955D01*
X143150D01*
X144679Y-293789D01*
X145552Y-292038D01*
X145989Y-289997D01*
X145552Y-287955D01*
X144242Y-286205D01*
X142713Y-285622D01*
X135945D01*
G01X171600Y-294955D02*
Y-277455D01*
X176840D01*
X178587Y-278330D01*
X179897Y-280372D01*
X180334Y-282705D01*
X179897Y-285038D01*
X178805Y-286788D01*
X176840Y-287664D01*
X171600D01*
G01X188008Y-277455D02*
X193467Y-294955D01*
X198926Y-277455D01*
G01X210967D02*
Y-294955D01*
G01X205945Y-277455D02*
X215989D01*
G01X21540Y-249955D02*
Y-232455D01*
X27217Y-247038D01*
X32894Y-232455D01*
Y-249955D01*
G01X44717D02*
X43407Y-249663D01*
X42097Y-248497D01*
X41223Y-246455D01*
X40787Y-244122D01*
X41223Y-241788D01*
X42097Y-239747D01*
X43407Y-238580D01*
X44717Y-238289D01*
X46027Y-238580D01*
X47337Y-239747D01*
X48210Y-241788D01*
X48429Y-244122D01*
X48210Y-246455D01*
X47337Y-248497D01*
X46027Y-249663D01*
X44717Y-249955D01*
G01X66147Y-232455D02*
Y-249955D01*
G01Y-247331D02*
X65274Y-248789D01*
X63963Y-249663D01*
X62435Y-249955D01*
X60689Y-249372D01*
X59379Y-247914D01*
X58505Y-246164D01*
X58287Y-244122D01*
X58505Y-242080D01*
X59379Y-240330D01*
X60689Y-238872D01*
X62435Y-238289D01*
X63963Y-238580D01*
X65055Y-239164D01*
X66147Y-240330D01*
G01X76442Y-242080D02*
X83429D01*
X82774Y-240038D01*
X81682Y-238872D01*
X80154Y-238289D01*
X78625Y-238580D01*
X77315Y-239455D01*
X76442Y-241497D01*
X76005Y-243247D01*
Y-244997D01*
X76442Y-246747D01*
X77534Y-248497D01*
X78844Y-249663D01*
X80372Y-249955D01*
X81900Y-249372D01*
X83429Y-247622D01*
G01X97217Y-249955D02*
Y-232455D01*
G01X252500Y-249955D02*
Y-232455D01*
X257740D01*
X259487Y-233330D01*
X260797Y-235372D01*
X261234Y-237705D01*
X260797Y-240038D01*
X259705Y-241788D01*
X257740Y-242664D01*
X252500D01*
G01X279170Y-233914D02*
X277860Y-233038D01*
X276332Y-232455D01*
X274585D01*
X272620Y-233330D01*
X271092Y-234788D01*
X270000Y-236539D01*
X269127Y-239455D01*
X268908Y-242080D01*
X269345Y-244705D01*
X270000Y-246455D01*
X271310Y-248205D01*
X272839Y-249372D01*
X274367Y-249955D01*
X275895D01*
X277424Y-249372D01*
X278734Y-248497D01*
X279826Y-247331D01*
G01X293613Y-240622D02*
X294487Y-239747D01*
X295142Y-238289D01*
X295579Y-236246D01*
X295142Y-234497D01*
X294269Y-233330D01*
X292740Y-232455D01*
X286845D01*
Y-249955D01*
X294050D01*
X295579Y-248789D01*
X296452Y-247038D01*
X296889Y-244997D01*
X296452Y-242955D01*
X295142Y-241205D01*
X293613Y-240622D01*
X286845D01*
G01X302817Y-255788D02*
X315917D01*
G01X321845Y-249955D02*
Y-232455D01*
X331889Y-249955D01*
Y-232455D01*
G01X344367Y-249955D02*
X342620Y-249663D01*
X341092Y-248497D01*
X339782Y-246747D01*
X338908Y-244705D01*
X338472Y-242372D01*
Y-240038D01*
X338908Y-237705D01*
X339782Y-235663D01*
X341092Y-233914D01*
X342620Y-232747D01*
X344367Y-232455D01*
X346113Y-232747D01*
X347642Y-233914D01*
X348952Y-235663D01*
X349826Y-237705D01*
X350262Y-240038D01*
Y-242372D01*
X349826Y-244705D01*
X348952Y-246747D01*
X347642Y-248497D01*
X346113Y-249663D01*
X344367Y-249955D01*
G01X265617Y-294955D02*
Y-277455D01*
X262997Y-280955D01*
G01Y-294955D02*
X268237D01*
G01X278314Y-292331D02*
X279623Y-293789D01*
X281152Y-294663D01*
X283117Y-294955D01*
X285082Y-294372D01*
X286610Y-293205D01*
X287702Y-291164D01*
X287920Y-288830D01*
X287484Y-286497D01*
X286392Y-285038D01*
X284863Y-283872D01*
X283335Y-283580D01*
X281807Y-283872D01*
X279842Y-285038D01*
X280497Y-277455D01*
X286392D01*
G01X296469Y-287664D02*
X297997Y-285622D01*
X299307Y-284455D01*
X301054Y-283872D01*
X302582Y-284455D01*
X303674Y-285622D01*
X304547Y-287372D01*
X304765Y-289413D01*
X304547Y-291164D01*
X303674Y-292914D01*
X302363Y-294372D01*
X300835Y-294955D01*
X299089Y-294372D01*
X297560Y-292622D01*
X296687Y-289997D01*
X296469Y-287080D01*
X296905Y-283289D01*
X297560Y-281246D01*
X298652Y-279205D01*
X300180Y-277747D01*
X301709Y-277455D01*
X303237Y-278038D01*
X304329Y-279497D01*
G01X313969Y-287664D02*
X315497Y-285622D01*
X316807Y-284455D01*
X318554Y-283872D01*
X320082Y-284455D01*
X321174Y-285622D01*
X322047Y-287372D01*
X322265Y-289413D01*
X322047Y-291164D01*
X321174Y-292914D01*
X319863Y-294372D01*
X318335Y-294955D01*
X316589Y-294372D01*
X315060Y-292622D01*
X314187Y-289997D01*
X313969Y-287080D01*
X314405Y-283289D01*
X315060Y-281246D01*
X316152Y-279205D01*
X317680Y-277747D01*
X319209Y-277455D01*
X320737Y-278038D01*
X321829Y-279497D01*
G01X331905Y-292914D02*
X333434Y-294372D01*
X335180Y-294955D01*
X336927Y-294372D01*
X338455Y-292622D01*
X339547Y-289997D01*
X339984Y-287372D01*
Y-284164D01*
X339547Y-281539D01*
X338455Y-279205D01*
X337145Y-278038D01*
X335617Y-277455D01*
X333870Y-278038D01*
X332560Y-279205D01*
X331687Y-280955D01*
X331250Y-283289D01*
X331687Y-285330D01*
X332779Y-287372D01*
X334089Y-288539D01*
X335617Y-288830D01*
X337363Y-288247D01*
X338674Y-286788D01*
X339984Y-284164D01*
G01X395208Y-232455D02*
X400667Y-249955D01*
X406126Y-232455D01*
G01X422534Y-249955D02*
X413800D01*
Y-232455D01*
X422534D01*
G01X419040Y-240913D02*
X413800D01*
G01X431300Y-249955D02*
Y-232455D01*
X436759D01*
X438505Y-233330D01*
X439597Y-234497D01*
X440034Y-236830D01*
X439597Y-239164D01*
X438287Y-240622D01*
X436759Y-241497D01*
X431300D01*
G01X436759D02*
X440034Y-249955D01*
G01X453167Y-250538D02*
X452730Y-250247D01*
Y-249663D01*
X453167Y-249372D01*
X453604Y-249663D01*
Y-250247D01*
X453167Y-250538D01*
G01X426917Y-294955D02*
Y-277455D01*
X424297Y-280955D01*
G01Y-294955D02*
X429537D01*
G01X528750Y-232455D02*
Y-249955D01*
X537484D01*
G01X554547D02*
Y-238289D01*
G01Y-240330D02*
X553674Y-239164D01*
X552363Y-238580D01*
X550835Y-238289D01*
X549307Y-238872D01*
X547997Y-240038D01*
X547123Y-241788D01*
X546687Y-244122D01*
X547123Y-246455D01*
X547997Y-248205D01*
X549307Y-249372D01*
X550835Y-249955D01*
X552363Y-249663D01*
X553674Y-248789D01*
X554547Y-247622D01*
G01X563532Y-255205D02*
X564842Y-255788D01*
X566589Y-255205D01*
X567680Y-254039D01*
X568554Y-252580D01*
X569863Y-247914D01*
X572702Y-238289D01*
G01X565715D02*
X569863Y-247914D01*
G01X582342Y-242080D02*
X589329D01*
X588674Y-240038D01*
X587582Y-238872D01*
X586054Y-238289D01*
X584525Y-238580D01*
X583215Y-239455D01*
X582342Y-241497D01*
X581905Y-243247D01*
Y-244997D01*
X582342Y-246747D01*
X583434Y-248497D01*
X584744Y-249663D01*
X586272Y-249955D01*
X587800Y-249372D01*
X589329Y-247622D01*
G01X600060Y-249955D02*
Y-238289D01*
G01Y-240622D02*
X601152Y-239455D01*
X602244Y-238580D01*
X603772Y-238289D01*
X604863Y-238580D01*
X606174Y-239455D01*
G01X601371Y-285622D02*
X600497Y-284747D01*
X599842Y-283289D01*
X599405Y-281246D01*
X599842Y-279497D01*
X600715Y-278330D01*
X602244Y-277455D01*
X608139D01*
Y-294955D01*
X600934D01*
X599405Y-293789D01*
X598532Y-292038D01*
X598095Y-289997D01*
X598532Y-287955D01*
X599842Y-286205D01*
X601371Y-285622D01*
X608139D01*
G01X590202Y-292622D02*
X588455Y-294080D01*
X586490Y-294955D01*
X584744D01*
X582997Y-294080D01*
X581687Y-292622D01*
X581032Y-290580D01*
X581469Y-288539D01*
X582560Y-286788D01*
X584525Y-285622D01*
X587145Y-285038D01*
X588674Y-283872D01*
X589329Y-281830D01*
X588892Y-279788D01*
X587800Y-278330D01*
X586272Y-277455D01*
X584744D01*
X583215Y-278038D01*
X581905Y-279497D01*
G01X570737Y-277455D02*
X565497D01*
G01X568117D02*
Y-294955D01*
G01X570737D02*
X565497D01*
G01X554984Y-277455D02*
Y-294955D01*
X546250D01*
G01X537920D02*
Y-277455D01*
G01X529624D02*
X537920Y-288247D01*
G01X528314Y-294955D02*
X534209Y-283289D01*
G01X670864Y-249955D02*
Y-232455D01*
X675230D01*
X676977Y-233330D01*
X678287Y-234497D01*
X679379Y-236246D01*
X680252Y-238289D01*
X680470Y-241205D01*
X680252Y-244122D01*
X679379Y-246164D01*
X678287Y-247914D01*
X676977Y-249080D01*
X675230Y-249955D01*
X670864D01*
G01X689892Y-242080D02*
X696879D01*
X696224Y-240038D01*
X695132Y-238872D01*
X693604Y-238289D01*
X692075Y-238580D01*
X690765Y-239455D01*
X689892Y-241497D01*
X689455Y-243247D01*
Y-244997D01*
X689892Y-246747D01*
X690984Y-248497D01*
X692294Y-249663D01*
X693822Y-249955D01*
X695350Y-249372D01*
X696879Y-247622D01*
G01X707392Y-247914D02*
X708484Y-249080D01*
X710012Y-249955D01*
X711322D01*
X712632Y-249372D01*
X713505Y-248497D01*
X713942Y-247331D01*
X713724Y-245580D01*
X712850Y-244705D01*
X708920Y-242955D01*
X708047Y-240913D01*
X708484Y-239455D01*
X709357Y-238580D01*
X710667Y-238289D01*
X711977Y-238580D01*
X713287Y-239455D01*
G01X728167Y-238289D02*
Y-249955D01*
G01Y-233622D02*
X727730Y-233330D01*
Y-232747D01*
X728167Y-232455D01*
X728604Y-232747D01*
Y-233330D01*
X728167Y-233622D01*
G01X742610Y-254330D02*
X744139Y-255497D01*
X745885Y-255788D01*
X747413Y-255497D01*
X748724Y-254039D01*
X749597Y-251997D01*
Y-238289D01*
G01Y-240622D02*
X748724Y-239455D01*
X747413Y-238580D01*
X745885Y-238289D01*
X744139Y-238872D01*
X743047Y-240038D01*
X742173Y-242080D01*
X741737Y-244122D01*
X741955Y-245872D01*
X742829Y-247914D01*
X744139Y-249372D01*
X745885Y-249955D01*
X747195Y-249663D01*
X748724Y-248497D01*
X749597Y-247331D01*
G01X759455Y-249955D02*
Y-238289D01*
G01Y-241205D02*
X760329Y-239747D01*
X761639Y-238580D01*
X763385Y-238289D01*
X764913Y-238580D01*
X766224Y-239747D01*
X766879Y-241788D01*
Y-249955D01*
G01X777392Y-242080D02*
X784379D01*
X783724Y-240038D01*
X782632Y-238872D01*
X781104Y-238289D01*
X779575Y-238580D01*
X778265Y-239455D01*
X777392Y-241497D01*
X776955Y-243247D01*
Y-244997D01*
X777392Y-246747D01*
X778484Y-248497D01*
X779794Y-249663D01*
X781322Y-249955D01*
X782850Y-249372D01*
X784379Y-247622D01*
G01X795110Y-249955D02*
Y-238289D01*
G01Y-240622D02*
X796202Y-239455D01*
X797294Y-238580D01*
X798822Y-238289D01*
X799913Y-238580D01*
X801224Y-239455D01*
G01X660367Y-277455D02*
X663423Y-294955D01*
X666917Y-277455D01*
X670410Y-294955D01*
X673467Y-277455D01*
G01X680050Y-294955D02*
Y-277455D01*
X685290D01*
X687037Y-278330D01*
X688347Y-280372D01*
X688784Y-282705D01*
X688347Y-285038D01*
X687255Y-286788D01*
X685290Y-287664D01*
X680050D01*
G01X697332Y-294955D02*
Y-277455D01*
G01X706502D02*
Y-294955D01*
G01Y-286205D02*
X697332D01*
G01X716579Y-289122D02*
X722255D01*
G01X732769Y-294955D02*
Y-277455D01*
X741065D01*
G01X738009Y-285913D02*
X732769D01*
G01X750050Y-277455D02*
Y-294955D01*
X758784D01*
G01X771917D02*
X770170Y-294663D01*
X768642Y-293497D01*
X767332Y-291747D01*
X766458Y-289705D01*
X766022Y-287372D01*
Y-285038D01*
X766458Y-282705D01*
X767332Y-280663D01*
X768642Y-278914D01*
X770170Y-277747D01*
X771917Y-277455D01*
X773663Y-277747D01*
X775192Y-278914D01*
X776502Y-280663D01*
X777376Y-282705D01*
X777812Y-285038D01*
Y-287372D01*
X777376Y-289705D01*
X776502Y-291747D01*
X775192Y-293497D01*
X773663Y-294663D01*
X771917Y-294955D01*
G01X785050D02*
Y-277455D01*
X790509D01*
X792255Y-278330D01*
X793347Y-279497D01*
X793784Y-281830D01*
X793347Y-284164D01*
X792037Y-285622D01*
X790509Y-286497D01*
X785050D01*
G01X790509D02*
X793784Y-294955D01*
G01X801458D02*
X806917Y-277455D01*
X812376Y-294955D01*
G01X810410Y-288830D02*
X803423D01*
G01X841867Y-294955D02*
Y-277455D01*
X839247Y-280955D01*
G01Y-294955D02*
X844487D01*
G01X859367D02*
Y-277455D01*
X856747Y-280955D01*
G01Y-294955D02*
X861987D01*
G01X872937Y-295538D02*
X880797Y-277455D01*
G01X894367Y-294955D02*
Y-277455D01*
X891747Y-280955D01*
G01Y-294955D02*
X896987D01*
G01X907719Y-287664D02*
X909247Y-285622D01*
X910557Y-284455D01*
X912304Y-283872D01*
X913832Y-284455D01*
X914924Y-285622D01*
X915797Y-287372D01*
X916015Y-289413D01*
X915797Y-291164D01*
X914924Y-292914D01*
X913613Y-294372D01*
X912085Y-294955D01*
X910339Y-294372D01*
X908810Y-292622D01*
X907937Y-289997D01*
X907719Y-287080D01*
X908155Y-283289D01*
X908810Y-281246D01*
X909902Y-279205D01*
X911430Y-277747D01*
X912959Y-277455D01*
X914487Y-278038D01*
X915579Y-279497D01*
G01X925437Y-295538D02*
X933297Y-277455D01*
G01X942719Y-280372D02*
X944029Y-278622D01*
X945557Y-277747D01*
X947304Y-277455D01*
X949487Y-278038D01*
X951015Y-279497D01*
X951452Y-281246D01*
X951234Y-282997D01*
X950360Y-284455D01*
X945994Y-287372D01*
X944029Y-289413D01*
X942719Y-292331D01*
X942282Y-294955D01*
X951452D01*
G01X964367Y-277455D02*
X962620Y-278038D01*
X961310Y-279497D01*
X960437Y-281246D01*
X959782Y-283580D01*
X959564Y-286205D01*
X959782Y-288830D01*
X960437Y-291164D01*
X961310Y-292914D01*
X962620Y-294372D01*
X964367Y-294955D01*
X966113Y-294372D01*
X967424Y-292914D01*
X968297Y-291164D01*
X968952Y-288830D01*
X969170Y-286205D01*
X968952Y-283580D01*
X968297Y-281246D01*
X967424Y-279497D01*
X966113Y-278038D01*
X964367Y-277455D01*
G01X981867Y-294955D02*
Y-277455D01*
X979247Y-280955D01*
G01Y-294955D02*
X984487D01*
G01X995219Y-287664D02*
X996747Y-285622D01*
X998057Y-284455D01*
X999804Y-283872D01*
X1001332Y-284455D01*
X1002424Y-285622D01*
X1003297Y-287372D01*
X1003515Y-289413D01*
X1003297Y-291164D01*
X1002424Y-292914D01*
X1001113Y-294372D01*
X999585Y-294955D01*
X997839Y-294372D01*
X996310Y-292622D01*
X995437Y-289997D01*
X995219Y-287080D01*
X995655Y-283289D01*
X996310Y-281246D01*
X997402Y-279205D01*
X998930Y-277747D01*
X1000459Y-277455D01*
X1001987Y-278038D01*
X1003079Y-279497D01*
G01X889564Y-249955D02*
Y-232455D01*
X893930D01*
X895677Y-233330D01*
X896987Y-234497D01*
X898079Y-236246D01*
X898952Y-238289D01*
X899170Y-241205D01*
X898952Y-244122D01*
X898079Y-246164D01*
X896987Y-247914D01*
X895677Y-249080D01*
X893930Y-249955D01*
X889564D01*
G01X915797D02*
Y-238289D01*
G01Y-240330D02*
X914924Y-239164D01*
X913613Y-238580D01*
X912085Y-238289D01*
X910557Y-238872D01*
X909247Y-240038D01*
X908373Y-241788D01*
X907937Y-244122D01*
X908373Y-246455D01*
X909247Y-248205D01*
X910557Y-249372D01*
X912085Y-249955D01*
X913613Y-249663D01*
X914924Y-248789D01*
X915797Y-247622D01*
G01X929367Y-232455D02*
Y-249955D01*
G01X926310Y-238289D02*
X932424D01*
G01X943592Y-242080D02*
X950579D01*
X949924Y-240038D01*
X948832Y-238872D01*
X947304Y-238289D01*
X945775Y-238580D01*
X944465Y-239455D01*
X943592Y-241497D01*
X943155Y-243247D01*
Y-244997D01*
X943592Y-246747D01*
X944684Y-248497D01*
X945994Y-249663D01*
X947522Y-249955D01*
X949050Y-249372D01*
X950579Y-247622D01*
G01X893701Y19685D02*
X889764D01*
G01D02*
Y-1D01*
G01X893701D02*
Y19685D01*
G01X889764Y1972440D02*
Y1992125D01*
G01X893701D02*
Y1972440D01*
G01D02*
X889764D01*
G01X982283Y19685D02*
X986220D01*
G01X982283Y-1D02*
Y19685D01*
G01Y1992125D02*
Y1972440D01*
G01D02*
X986220D01*
G01Y19685D02*
Y-1D01*
G01Y1972440D02*
Y1992125D01*
M02*
